FILE_TYPE = MACRO_DRAWING;
SET COLOR_WIRE YELLOW;
SET COLOR_PROP ORANGE;
SET COLOR_DOT WHITE;
SET COLOR_ARC YELLOW;
SET COLOR_BODY GREEN;
SET COLOR_NOTE PURPLE;
SET PROP_DISPLAY VALUE;
SET PAGE_NUMBER P191;
FORCEADD OFFPAGE..1
(-7875 4050);
FORCEPROP 2 LAST $XR4 191 
J 0
(-8607 4050);
DISPLAY 0.638298 (-8607 4050);
PAINT MONO (-8607 4050);
FORCEPROP 2 LAST $XR3 189 
J 0
(-8487 4050);
DISPLAY 0.638298 (-8487 4050);
PAINT MONO (-8487 4050);
FORCEPROP 2 LAST $XR2 188 
J 0
(-8367 4050);
DISPLAY 0.638298 (-8367 4050);
PAINT MONO (-8367 4050);
FORCEPROP 2 LAST $XR1 187 
J 0
(-8247 4050);
DISPLAY 0.638298 (-8247 4050);
PAINT MONO (-8247 4050);
FORCEPROP 2 LAST $XR0 186 
J 0
(-8127 4050);
DISPLAY 0.638298 (-8127 4050);
PAINT MONO (-8127 4050);
FORCEPROP 2 LAST PATH I1
J 0
(-7825 4125);
DISPLAY 1.021277 (-7825 4125);
DISPLAY INVISIBLE (-7825 4125);
FORCEPROP 1 LAST COMMENT_BODY TRUE
J 0
(-7750 3950);
DISPLAY 0.872340 (-7750 3950);
PAINT GREEN (-7750 3950);
DISPLAY INVISIBLE (-7750 3950);
FORCEPROP 1 LAST OFFPAGE TRUE
J 0
(-7550 3925);
DISPLAY 0.872340 (-7550 3925);
PAINT GREEN (-7550 3925);
DISPLAY INVISIBLE (-7550 3925);
FORCEPROP 2 LAST CDS_LIB standard
J 0
(-7875 4050);
DISPLAY INVISIBLE (-7875 4050);
FORCEADD UNIVERSAL_GND..1
(-5250 3425);
FORCEPROP 3 LASTPIN (-5250 3475) SIG_NAME GND\g
J 0
(-5240 3485);
DISPLAY 0.659574 (-5240 3485);
PAINT MONO (-5240 3485);
DISPLAY INVISIBLE (-5240 3485);
FORCEPROP 2 LAST CDS_LIB pure_quanta_power
J 0
(-5250 3425);
DISPLAY INVISIBLE (-5250 3425);
FORCEPROP 1 LAST PATH I16
J 0
(-5175 3425);
DISPLAY 0.872340 (-5175 3425);
PAINT AQUA (-5175 3425);
DISPLAY INVISIBLE (-5175 3425);
FORCEPROP 1 LAST HDL_POWER GND
J 1
(-5225 3350);
DISPLAY 0.872340 (-5225 3350);
PAINT GREEN (-5225 3350);
DISPLAY INVISIBLE (-5225 3350);
FORCEADD Q_RES..1
(-3975 2950);
FORCEPROP 1 LAST LOCATION PR216
J 0
(-4000 3000);
DISPLAY 0.489362 (-4000 3000);
PAINT SKYBLUE (-4000 3000);
FORCEPROP 0 LAST $SEC 1
J 0
(-3975 3025);
DISPLAY 0.680851 (-3975 3025);
PAINT MONO (-3975 3025);
DISPLAY INVISIBLE (-3975 3025);
FORCEPROP 0 LAST CDS_SEC 1
J 0
(-3975 3025);
DISPLAY 1.021277 (-3975 3025);
DISPLAY INVISIBLE (-3975 3025);
FORCEPROP 1 LASTPIN (-4075 2950) $PN 1
J 0
(-4063 2962);
DISPLAY 0.489362 (-4063 2962);
PAINT MONO (-4063 2962);
FORCEPROP 1 LASTPIN (-3875 2950) $PN 2
J 0
(-3913 2962);
DISPLAY 0.489362 (-3913 2962);
PAINT MONO (-3913 2962);
FORCEPROP 1 LAST WATTAGE 1/16W
J 0
(-3875 2900);
DISPLAY 0.489362 (-3875 2900);
PAINT SKYBLUE (-3875 2900);
FORCEPROP 1 LAST MATERIAL CHIP
J 0
(-4225 2850);
DISPLAY 0.489362 (-4225 2850);
PAINT SKYBLUE (-4225 2850);
FORCEPROP 1 LAST TOLERANCE 5%
J 0
(-3850 2975);
DISPLAY 0.489362 (-3850 2975);
PAINT SKYBLUE (-3850 2975);
FORCEPROP 1 LAST VALUE 0
J 2
(-4100 2975);
DISPLAY 0.489362 (-4100 2975);
PAINT SKYBLUE (-4100 2975);
FORCEPROP 1 LAST PART_NUMBER CS00002JB38
J 0
(-4225 2900);
DISPLAY 0.489362 (-4225 2900);
PAINT SKYBLUE (-4225 2900);
FORCEPROP 1 LAST PACK_TYPE 0402LF
J 0
(-3875 2850);
DISPLAY 0.489362 (-3875 2850);
PAINT SKYBLUE (-3875 2850);
FORCEPROP 2 LAST CDS_LIB pure_quanta
J 0
(-3975 2950);
DISPLAY INVISIBLE (-3975 2950);
FORCEPROP 1 LAST PATH I17
J 0
(-4025 3100);
DISPLAY 0.978723 (-4025 3100);
PAINT WHITE (-4025 3100);
DISPLAY INVISIBLE (-4025 3100);
FORCEADD Q_RES..1
(-4450 4500);
FORCEPROP 1 LAST LOCATION PR215
J 0
(-4475 4550);
DISPLAY 0.489362 (-4475 4550);
PAINT SKYBLUE (-4475 4550);
FORCEPROP 0 LAST $SEC 1
J 0
(-4425 4575);
DISPLAY 0.680851 (-4425 4575);
PAINT MONO (-4425 4575);
DISPLAY INVISIBLE (-4425 4575);
FORCEPROP 0 LAST CDS_SEC 1
J 0
(-4425 4575);
DISPLAY 1.021277 (-4425 4575);
DISPLAY INVISIBLE (-4425 4575);
FORCEPROP 1 LASTPIN (-4550 4500) $PN 1
J 0
(-4538 4512);
DISPLAY 0.489362 (-4538 4512);
PAINT MONO (-4538 4512);
FORCEPROP 1 LASTPIN (-4350 4500) $PN 2
J 0
(-4388 4512);
DISPLAY 0.489362 (-4388 4512);
PAINT MONO (-4388 4512);
FORCEPROP 1 LAST PACK_TYPE 0402LF
J 0
(-4350 4400);
DISPLAY 0.489362 (-4350 4400);
PAINT SKYBLUE (-4350 4400);
FORCEPROP 1 LAST TOLERANCE 1%
J 0
(-4325 4525);
DISPLAY 0.489362 (-4325 4525);
PAINT SKYBLUE (-4325 4525);
FORCEPROP 1 LAST MATERIAL CHIP
J 0
(-4700 4400);
DISPLAY 0.489362 (-4700 4400);
PAINT SKYBLUE (-4700 4400);
FORCEPROP 1 LAST WATTAGE 1/16W
J 0
(-4350 4450);
DISPLAY 0.489362 (-4350 4450);
PAINT SKYBLUE (-4350 4450);
FORCEPROP 1 LAST VALUE 4.7
J 2
(-4575 4525);
DISPLAY 0.489362 (-4575 4525);
PAINT SKYBLUE (-4575 4525);
FORCEPROP 1 LAST PART_NUMBER CS-4702FB19
J 0
(-4700 4450);
DISPLAY 0.489362 (-4700 4450);
PAINT SKYBLUE (-4700 4450);
FORCEPROP 1 LAST PATH I18
J 0
(-4500 4650);
DISPLAY 0.978723 (-4500 4650);
PAINT WHITE (-4500 4650);
DISPLAY INVISIBLE (-4500 4650);
FORCEPROP 2 LAST CDS_LIB pure_quanta
J 0
(-4450 4500);
DISPLAY INVISIBLE (-4450 4500);
FORCEADD UNIVERSAL_GND..1
(-7650 3600);
FORCEPROP 3 LASTPIN (-7650 3650) SIG_NAME GND\g
J 0
(-7640 3660);
DISPLAY 0.659574 (-7640 3660);
PAINT MONO (-7640 3660);
DISPLAY INVISIBLE (-7640 3660);
FORCEPROP 2 LAST CDS_LIB pure_quanta_power
J 0
(-7650 3600);
DISPLAY INVISIBLE (-7650 3600);
FORCEPROP 1 LAST PATH I2
J 0
(-7575 3600);
DISPLAY 0.872340 (-7575 3600);
PAINT AQUA (-7575 3600);
DISPLAY INVISIBLE (-7575 3600);
FORCEPROP 1 LAST HDL_POWER GND
J 1
(-7625 3525);
DISPLAY 0.872340 (-7625 3525);
PAINT GREEN (-7625 3525);
DISPLAY INVISIBLE (-7625 3525);
FORCEADD Q_CAP..1
(-4625 5025);
FORCEPROP 1 LAST LOCATION PC349_3
J 0
(-4575 5125);
DISPLAY 0.489362 (-4575 5125);
PAINT SKYBLUE (-4575 5125);
FORCEPROP 0 LAST $SEC 1
J 0
(-4575 5150);
DISPLAY 0.680851 (-4575 5150);
PAINT MONO (-4575 5150);
DISPLAY INVISIBLE (-4575 5150);
FORCEPROP 0 LAST CDS_SEC 1
J 0
(-4575 5150);
DISPLAY 1.021277 (-4575 5150);
DISPLAY INVISIBLE (-4575 5150);
FORCEPROP 1 LASTPIN (-4625 5125) $PN 1
J 0
(-4615 5105);
DISPLAY 0.489362 (-4615 5105);
PAINT MONO (-4615 5105);
FORCEPROP 1 LASTPIN (-4625 4925) $PN 2
J 0
(-4615 4905);
DISPLAY 0.489362 (-4615 4905);
PAINT MONO (-4615 4905);
FORCEPROP 1 LAST MATERIAL X6S
J 0
(-4575 4925);
DISPLAY 0.489362 (-4575 4925);
PAINT SKYBLUE (-4575 4925);
FORCEPROP 1 LAST TOLERANCE 10%
J 0
(-4575 4975);
DISPLAY 0.489362 (-4575 4975);
PAINT SKYBLUE (-4575 4975);
FORCEPROP 1 LAST VALUE 1UF
J 0
(-4575 5075);
DISPLAY 0.489362 (-4575 5075);
PAINT SKYBLUE (-4575 5075);
FORCEPROP 1 LAST PART_NUMBER CH5104KEB02
J 0
(-4575 4875);
DISPLAY 0.489362 (-4575 4875);
PAINT SKYBLUE (-4575 4875);
FORCEPROP 1 LAST VOLTAGE 25V
J 0
(-4575 5025);
DISPLAY 0.489362 (-4575 5025);
PAINT SKYBLUE (-4575 5025);
FORCEPROP 1 LAST PACK_TYPE C0402
J 0
(-4575 4825);
DISPLAY 0.489362 (-4575 4825);
PAINT SKYBLUE (-4575 4825);
FORCEPROP 2 LAST CDS_LIB pure_quanta
J 0
(-4625 5025);
DISPLAY INVISIBLE (-4625 5025);
FORCEPROP 1 LAST PATH I20
J 0
(-4575 5175);
DISPLAY 0.978723 (-4575 5175);
PAINT WHITE (-4575 5175);
DISPLAY INVISIBLE (-4575 5175);
FORCEADD Q_CAP..1
(-4300 5025);
FORCEPROP 1 LAST LOCATION PC350_3
J 0
(-4250 5125);
DISPLAY 0.489362 (-4250 5125);
PAINT SKYBLUE (-4250 5125);
FORCEPROP 0 LAST $SEC 1
J 0
(-4250 5150);
DISPLAY 0.680851 (-4250 5150);
PAINT MONO (-4250 5150);
DISPLAY INVISIBLE (-4250 5150);
FORCEPROP 0 LAST CDS_SEC 1
J 0
(-4250 5150);
DISPLAY 1.021277 (-4250 5150);
DISPLAY INVISIBLE (-4250 5150);
FORCEPROP 1 LASTPIN (-4300 5125) $PN 1
J 0
(-4290 5105);
DISPLAY 0.489362 (-4290 5105);
PAINT MONO (-4290 5105);
FORCEPROP 1 LASTPIN (-4300 4925) $PN 2
J 0
(-4290 4905);
DISPLAY 0.489362 (-4290 4905);
PAINT MONO (-4290 4905);
FORCEPROP 1 LAST MATERIAL X6S
J 0
(-4250 4925);
DISPLAY 0.489362 (-4250 4925);
PAINT SKYBLUE (-4250 4925);
FORCEPROP 1 LAST TOLERANCE 10%
J 0
(-4250 4975);
DISPLAY 0.489362 (-4250 4975);
PAINT SKYBLUE (-4250 4975);
FORCEPROP 1 LAST VALUE 10UF
J 0
(-4250 5075);
DISPLAY 0.489362 (-4250 5075);
PAINT SKYBLUE (-4250 5075);
FORCEPROP 1 LAST PART_NUMBER CH6104KEA00
J 0
(-4250 4875);
DISPLAY 0.489362 (-4250 4875);
PAINT SKYBLUE (-4250 4875);
FORCEPROP 1 LAST VOLTAGE 25V
J 0
(-4250 5025);
DISPLAY 0.489362 (-4250 5025);
PAINT SKYBLUE (-4250 5025);
FORCEPROP 1 LAST PACK_TYPE C0805
J 0
(-4250 4825);
DISPLAY 0.489362 (-4250 4825);
PAINT SKYBLUE (-4250 4825);
FORCEPROP 2 LAST CDS_LIB pure_quanta
J 0
(-4300 5025);
DISPLAY INVISIBLE (-4300 5025);
FORCEPROP 1 LAST PATH I21
J 0
(-4250 5175);
DISPLAY 0.978723 (-4250 5175);
PAINT WHITE (-4250 5175);
DISPLAY INVISIBLE (-4250 5175);
FORCEADD Q_CAP..1
(-3975 5025);
FORCEPROP 1 LAST LOCATION PC351_3
J 0
(-3925 5125);
DISPLAY 0.489362 (-3925 5125);
PAINT SKYBLUE (-3925 5125);
FORCEPROP 0 LAST $SEC 1
J 0
(-3925 5150);
DISPLAY 0.680851 (-3925 5150);
PAINT MONO (-3925 5150);
DISPLAY INVISIBLE (-3925 5150);
FORCEPROP 0 LAST CDS_SEC 1
J 0
(-3925 5150);
DISPLAY 1.021277 (-3925 5150);
DISPLAY INVISIBLE (-3925 5150);
FORCEPROP 1 LASTPIN (-3975 5125) $PN 1
J 0
(-3965 5105);
DISPLAY 0.489362 (-3965 5105);
PAINT MONO (-3965 5105);
FORCEPROP 1 LASTPIN (-3975 4925) $PN 2
J 0
(-3965 4905);
DISPLAY 0.489362 (-3965 4905);
PAINT MONO (-3965 4905);
FORCEPROP 1 LAST MATERIAL X6S
J 0
(-3925 4925);
DISPLAY 0.489362 (-3925 4925);
PAINT SKYBLUE (-3925 4925);
FORCEPROP 1 LAST TOLERANCE 10%
J 0
(-3925 4975);
DISPLAY 0.489362 (-3925 4975);
PAINT SKYBLUE (-3925 4975);
FORCEPROP 1 LAST VALUE 10UF
J 0
(-3925 5075);
DISPLAY 0.489362 (-3925 5075);
PAINT SKYBLUE (-3925 5075);
FORCEPROP 1 LAST VOLTAGE 25V
J 0
(-3925 5025);
DISPLAY 0.489362 (-3925 5025);
PAINT SKYBLUE (-3925 5025);
FORCEPROP 1 LAST PACK_TYPE C0805
J 0
(-3925 4825);
DISPLAY 0.489362 (-3925 4825);
PAINT SKYBLUE (-3925 4825);
FORCEPROP 1 LAST PART_NUMBER CH6104KEA00
J 0
(-3925 4875);
DISPLAY 0.489362 (-3925 4875);
PAINT SKYBLUE (-3925 4875);
FORCEPROP 2 LAST CDS_LIB pure_quanta
J 0
(-3975 5025);
DISPLAY INVISIBLE (-3975 5025);
FORCEPROP 1 LAST PATH I22
J 0
(-3925 5175);
DISPLAY 0.978723 (-3925 5175);
PAINT WHITE (-3925 5175);
DISPLAY INVISIBLE (-3925 5175);
FORCEADD UNIVERSAL_GND..1
(-3300 4700);
FORCEPROP 3 LASTPIN (-3300 4750) SIG_NAME GND\g
J 0
(-3290 4760);
DISPLAY 0.659574 (-3290 4760);
PAINT MONO (-3290 4760);
DISPLAY INVISIBLE (-3290 4760);
FORCEPROP 2 LAST CDS_LIB pure_quanta_power
J 0
(-3300 4700);
DISPLAY INVISIBLE (-3300 4700);
FORCEPROP 1 LAST PATH I23
J 0
(-3225 4700);
DISPLAY 0.872340 (-3225 4700);
PAINT AQUA (-3225 4700);
DISPLAY INVISIBLE (-3225 4700);
FORCEPROP 1 LAST HDL_POWER GND
J 1
(-3275 4625);
DISPLAY 0.872340 (-3275 4625);
PAINT GREEN (-3275 4625);
DISPLAY INVISIBLE (-3275 4625);
FORCEADD Q_CAP..1
(-1400 3975);
FORCEPROP 1 LAST LOCATION PC354_3
J 0
(-1350 4075);
DISPLAY 0.489362 (-1350 4075);
PAINT SKYBLUE (-1350 4075);
FORCEPROP 0 LAST $SEC 1
J 0
(-1350 4100);
DISPLAY 0.680851 (-1350 4100);
PAINT MONO (-1350 4100);
DISPLAY INVISIBLE (-1350 4100);
FORCEPROP 0 LAST CDS_SEC 1
J 0
(-1350 4100);
DISPLAY 1.021277 (-1350 4100);
DISPLAY INVISIBLE (-1350 4100);
FORCEPROP 1 LASTPIN (-1400 4075) $PN 1
J 0
(-1390 4055);
DISPLAY 0.489362 (-1390 4055);
PAINT MONO (-1390 4055);
FORCEPROP 1 LASTPIN (-1400 3875) $PN 2
J 0
(-1390 3855);
DISPLAY 0.489362 (-1390 3855);
PAINT MONO (-1390 3855);
FORCEPROP 1 LAST MATERIAL X6S
J 0
(-1350 3875);
DISPLAY 0.489362 (-1350 3875);
PAINT SKYBLUE (-1350 3875);
FORCEPROP 1 LAST TOLERANCE 20%
J 0
(-1350 3925);
DISPLAY 0.489362 (-1350 3925);
PAINT SKYBLUE (-1350 3925);
FORCEPROP 1 LAST VALUE 22UF
J 0
(-1350 4025);
DISPLAY 0.489362 (-1350 4025);
PAINT SKYBLUE (-1350 4025);
FORCEPROP 1 LAST PART_NUMBER TMP_QCH622KMEA01
J 0
(-1350 3825);
DISPLAY 0.489362 (-1350 3825);
PAINT SKYBLUE (-1350 3825);
FORCEPROP 1 LAST VOLTAGE 4V
J 0
(-1350 3975);
DISPLAY 0.489362 (-1350 3975);
PAINT SKYBLUE (-1350 3975);
FORCEPROP 1 LAST PACK_TYPE 0805
J 0
(-1350 3775);
DISPLAY 0.489362 (-1350 3775);
PAINT SKYBLUE (-1350 3775);
FORCEPROP 2 LAST CDS_LIB pure_quanta
J 0
(-1400 3975);
DISPLAY INVISIBLE (-1400 3975);
FORCEPROP 1 LAST PATH I25
J 0
(-1350 4125);
DISPLAY 0.978723 (-1350 4125);
PAINT WHITE (-1350 4125);
DISPLAY INVISIBLE (-1350 4125);
FORCEADD Q_CAP..1
(-3675 5025);
FORCEPROP 1 LAST LOCATION PC352_3
J 0
(-3625 5125);
DISPLAY 0.489362 (-3625 5125);
PAINT SKYBLUE (-3625 5125);
FORCEPROP 0 LAST $SEC 1
J 0
(-3625 5150);
DISPLAY 0.680851 (-3625 5150);
PAINT MONO (-3625 5150);
DISPLAY INVISIBLE (-3625 5150);
FORCEPROP 0 LAST CDS_SEC 1
J 0
(-3625 5150);
DISPLAY 1.021277 (-3625 5150);
DISPLAY INVISIBLE (-3625 5150);
FORCEPROP 1 LASTPIN (-3675 5125) $PN 1
J 0
(-3665 5105);
DISPLAY 0.489362 (-3665 5105);
PAINT MONO (-3665 5105);
FORCEPROP 1 LASTPIN (-3675 4925) $PN 2
J 0
(-3665 4905);
DISPLAY 0.489362 (-3665 4905);
PAINT MONO (-3665 4905);
FORCEPROP 1 LAST MATERIAL X6S
J 0
(-3625 4925);
DISPLAY 0.489362 (-3625 4925);
PAINT SKYBLUE (-3625 4925);
FORCEPROP 1 LAST VALUE 10UF
J 0
(-3625 5075);
DISPLAY 0.489362 (-3625 5075);
PAINT SKYBLUE (-3625 5075);
FORCEPROP 1 LAST PART_NUMBER CH6104KEA00
J 0
(-3625 4875);
DISPLAY 0.489362 (-3625 4875);
PAINT SKYBLUE (-3625 4875);
FORCEPROP 1 LAST VOLTAGE 25V
J 0
(-3625 5025);
DISPLAY 0.489362 (-3625 5025);
PAINT SKYBLUE (-3625 5025);
FORCEPROP 1 LAST PACK_TYPE C0805
J 0
(-3625 4825);
DISPLAY 0.489362 (-3625 4825);
PAINT SKYBLUE (-3625 4825);
FORCEPROP 1 LAST TOLERANCE 10%
J 0
(-3625 4975);
DISPLAY 0.489362 (-3625 4975);
PAINT SKYBLUE (-3625 4975);
FORCEPROP 2 LAST CDS_LIB pure_quanta
J 0
(-3675 5025);
DISPLAY INVISIBLE (-3675 5025);
FORCEPROP 1 LAST PATH I26
J 0
(-3625 5175);
DISPLAY 0.978723 (-3625 5175);
PAINT WHITE (-3625 5175);
DISPLAY INVISIBLE (-3625 5175);
FORCEADD VCC_CORE..1
(-3300 5300);
FORCEPROP 3 LASTPIN (-3300 5250) SIG_NAME SW_P12V_STBY_PVDDCR_SOC_P1_FLT\g
J 0
(-3290 5260);
DISPLAY 0.659574 (-3290 5260);
PAINT MONO (-3290 5260);
DISPLAY INVISIBLE (-3290 5260);
FORCEPROP 1 LAST HDL_POWER SW_P12V_STBY_PVDDCR_SOC_P1_FLT
J 1
(-3300 5350);
DISPLAY 0.489362 (-3300 5350);
PAINT GREEN (-3300 5350);
FORCEPROP 2 LAST CDS_LIB pure_quanta_power
J 0
(-3300 5300);
DISPLAY INVISIBLE (-3300 5300);
FORCEPROP 1 LAST PATH I27
J 0
(-3250 5325);
DISPLAY 0.872340 (-3250 5325);
PAINT AQUA (-3250 5325);
DISPLAY INVISIBLE (-3250 5325);
FORCEADD UNIVERSAL_GND..1
(-975 3625);
FORCEPROP 3 LASTPIN (-975 3675) SIG_NAME GND\g
J 0
(-965 3685);
DISPLAY 0.659574 (-965 3685);
PAINT MONO (-965 3685);
DISPLAY INVISIBLE (-965 3685);
FORCEPROP 2 LAST CDS_LIB pure_quanta_power
J 0
(-975 3625);
DISPLAY INVISIBLE (-975 3625);
FORCEPROP 1 LAST PATH I28
J 0
(-900 3625);
DISPLAY 0.872340 (-900 3625);
PAINT AQUA (-900 3625);
DISPLAY INVISIBLE (-900 3625);
FORCEPROP 1 LAST HDL_POWER GND
J 1
(-950 3550);
DISPLAY 0.872340 (-950 3550);
PAINT GREEN (-950 3550);
DISPLAY INVISIBLE (-950 3550);
FORCEADD Q_CAP..1
(-975 3975);
FORCEPROP 1 LAST LOCATION PC355_3
J 0
(-925 4075);
DISPLAY 0.489362 (-925 4075);
PAINT SKYBLUE (-925 4075);
FORCEPROP 0 LAST $SEC 1
J 0
(-925 4100);
DISPLAY 0.680851 (-925 4100);
PAINT MONO (-925 4100);
DISPLAY INVISIBLE (-925 4100);
FORCEPROP 0 LAST CDS_SEC 1
J 0
(-925 4100);
DISPLAY 1.021277 (-925 4100);
DISPLAY INVISIBLE (-925 4100);
FORCEPROP 1 LASTPIN (-975 4075) $PN 1
J 0
(-965 4055);
DISPLAY 0.489362 (-965 4055);
PAINT MONO (-965 4055);
FORCEPROP 1 LASTPIN (-975 3875) $PN 2
J 0
(-965 3855);
DISPLAY 0.489362 (-965 3855);
PAINT MONO (-965 3855);
FORCEPROP 1 LAST MATERIAL X6S
J 0
(-925 3875);
DISPLAY 0.489362 (-925 3875);
PAINT SKYBLUE (-925 3875);
FORCEPROP 1 LAST TOLERANCE 20%
J 0
(-925 3925);
DISPLAY 0.489362 (-925 3925);
PAINT SKYBLUE (-925 3925);
FORCEPROP 1 LAST VALUE 22UF
J 0
(-925 4025);
DISPLAY 0.489362 (-925 4025);
PAINT SKYBLUE (-925 4025);
FORCEPROP 1 LAST PART_NUMBER TMP_QCH622KMEA01
J 0
(-925 3825);
DISPLAY 0.489362 (-925 3825);
PAINT SKYBLUE (-925 3825);
FORCEPROP 1 LAST VOLTAGE 4V
J 0
(-925 3975);
DISPLAY 0.489362 (-925 3975);
PAINT SKYBLUE (-925 3975);
FORCEPROP 1 LAST PACK_TYPE 0805
J 0
(-925 3775);
DISPLAY 0.489362 (-925 3775);
PAINT SKYBLUE (-925 3775);
FORCEPROP 2 LAST CDS_LIB pure_quanta
J 0
(-975 3975);
DISPLAY INVISIBLE (-975 3975);
FORCEPROP 1 LAST PATH I29
J 0
(-925 4125);
DISPLAY 0.978723 (-925 4125);
PAINT WHITE (-925 4125);
DISPLAY INVISIBLE (-925 4125);
FORCEADD UNIVERSAL_GND..1
(-7300 3675);
FORCEPROP 3 LASTPIN (-7300 3725) SIG_NAME GND\g
J 0
(-7290 3735);
DISPLAY 0.659574 (-7290 3735);
PAINT MONO (-7290 3735);
DISPLAY INVISIBLE (-7290 3735);
FORCEPROP 2 LAST CDS_LIB pure_quanta_power
J 0
(-7300 3675);
DISPLAY INVISIBLE (-7300 3675);
FORCEPROP 1 LAST PATH I3
J 0
(-7225 3675);
DISPLAY 0.872340 (-7225 3675);
PAINT AQUA (-7225 3675);
DISPLAY INVISIBLE (-7225 3675);
FORCEPROP 1 LAST HDL_POWER GND
J 1
(-7275 3600);
DISPLAY 0.872340 (-7275 3600);
PAINT GREEN (-7275 3600);
DISPLAY INVISIBLE (-7275 3600);
FORCEADD VCC_CORE..1
(-975 4300);
FORCEPROP 3 LASTPIN (-975 4250) SIG_NAME PVDDCR_SOC_P1\g
J 0
(-965 4260);
DISPLAY 0.659574 (-965 4260);
PAINT MONO (-965 4260);
DISPLAY INVISIBLE (-965 4260);
FORCEPROP 1 LAST HDL_POWER PVDDCR_SOC_P1
J 1
(-975 4350);
DISPLAY 0.489362 (-975 4350);
PAINT GREEN (-975 4350);
FORCEPROP 2 LAST CDS_LIB pure_quanta_power
J 0
(-975 4300);
DISPLAY INVISIBLE (-975 4300);
FORCEPROP 1 LAST PATH I30
J 0
(-925 4325);
DISPLAY 0.872340 (-925 4325);
PAINT AQUA (-925 4325);
DISPLAY INVISIBLE (-925 4325);
FORCEADD Q_INDUCTOR4P_14..1
(-2625 4025);
FORCEPROP 1 LAST LOCATION PL38
J 0
(-2850 4280);
DISPLAY 0.489362 (-2850 4280);
PAINT SKYBLUE (-2850 4280);
FORCEPROP 0 LAST $SEC 1
J 0
(-2850 4425);
DISPLAY 0.680851 (-2850 4425);
PAINT MONO (-2850 4425);
DISPLAY INVISIBLE (-2850 4425);
FORCEPROP 0 LAST CDS_SEC 1
J 0
(-2850 4425);
DISPLAY 1.021277 (-2850 4425);
DISPLAY INVISIBLE (-2850 4425);
FORCEPROP 0 LASTPIN (-3025 4150) $PN 1
J 2
(-3035 4160);
DISPLAY 0.489362 (-3035 4160);
PAINT MONO (-3035 4160);
FORCEPROP 0 LASTPIN (-3025 3900) $PN 2
J 2
(-3035 3910);
DISPLAY 0.489362 (-3035 3910);
PAINT MONO (-3035 3910);
FORCEPROP 0 LASTPIN (-2225 3900) $PN 3
J 0
(-2215 3910);
DISPLAY 0.489362 (-2215 3910);
PAINT MONO (-2215 3910);
FORCEPROP 0 LASTPIN (-2225 4150) $PN 4
J 0
(-2215 4160);
DISPLAY 0.489362 (-2215 4160);
PAINT MONO (-2215 4160);
FORCEPROP 2 LAST PART_TYPE SMLF
J 0
(-2850 4375);
DISPLAY 1.021277 (-2850 4375);
FORCEPROP 1 LAST MATERIAL IND
J 0
(-2850 4235);
DISPLAY 0.489362 (-2850 4235);
PAINT SKYBLUE (-2850 4235);
FORCEPROP 2 LAST VALUE 150NH
J 0
(-2850 4325);
DISPLAY 0.489362 (-2850 4325);
PAINT SKYBLUE (-2850 4325);
FORCEPROP 1 LAST PART_NUMBER CV+15^0TZ04
J 0
(-2850 4185);
DISPLAY 0.489362 (-2850 4185);
PAINT SKYBLUE (-2850 4185);
FORCEPROP 2 LAST CDS_LIB pure_quanta
J 0
(-2625 4025);
DISPLAY INVISIBLE (-2625 4025);
FORCEPROP 1 LAST NEEDS_NO_SIZE TRUE
J 0
(-2625 4025);
DISPLAY 0.468085 (-2625 4025);
PAINT GREEN (-2625 4025);
DISPLAY INVISIBLE (-2625 4025);
FORCEPROP 1 LAST PATH I31
J 0
(-2425 4180);
DISPLAY 0.723404 (-2425 4180);
PAINT GREEN (-2425 4180);
DISPLAY INVISIBLE (-2425 4180);
FORCEADD Q_CAP..1
(-3475 4375);
FORCEPROP 1 LAST LOCATION PC353
J 0
(-3425 4500);
DISPLAY 0.489362 (-3425 4500);
PAINT SKYBLUE (-3425 4500);
FORCEPROP 0 LAST $SEC 1
J 0
(-3425 4525);
DISPLAY 0.680851 (-3425 4525);
PAINT MONO (-3425 4525);
DISPLAY INVISIBLE (-3425 4525);
FORCEPROP 0 LAST CDS_SEC 1
J 0
(-3425 4525);
DISPLAY 1.021277 (-3425 4525);
DISPLAY INVISIBLE (-3425 4525);
FORCEPROP 1 LASTPIN (-3475 4475) $PN 1
J 0
(-3465 4455);
DISPLAY 0.489362 (-3465 4455);
PAINT MONO (-3465 4455);
FORCEPROP 1 LASTPIN (-3475 4275) $PN 2
J 0
(-3465 4255);
DISPLAY 0.489362 (-3465 4255);
PAINT MONO (-3465 4255);
FORCEPROP 1 LAST MATERIAL X7R
J 0
(-3425 4300);
DISPLAY 0.489362 (-3425 4300);
PAINT SKYBLUE (-3425 4300);
FORCEPROP 1 LAST TOLERANCE 10%
J 0
(-3425 4350);
DISPLAY 0.489362 (-3425 4350);
PAINT SKYBLUE (-3425 4350);
FORCEPROP 1 LAST VALUE 0.22UF
J 0
(-3425 4450);
DISPLAY 0.489362 (-3425 4450);
PAINT SKYBLUE (-3425 4450);
FORCEPROP 1 LAST PART_NUMBER CH4223K1B00
J 0
(-3425 4250);
DISPLAY 0.489362 (-3425 4250);
PAINT SKYBLUE (-3425 4250);
FORCEPROP 1 LAST VOLTAGE 16V
J 0
(-3425 4400);
DISPLAY 0.489362 (-3425 4400);
PAINT SKYBLUE (-3425 4400);
FORCEPROP 1 LAST PACK_TYPE 0402
J 0
(-3425 4200);
DISPLAY 0.489362 (-3425 4200);
PAINT SKYBLUE (-3425 4200);
FORCEPROP 2 LAST CDS_LIB pure_quanta
J 0
(-3475 4375);
DISPLAY INVISIBLE (-3475 4375);
FORCEPROP 1 LAST PATH I32
J 0
(-3425 4525);
DISPLAY 0.978723 (-3425 4525);
PAINT WHITE (-3425 4525);
DISPLAY INVISIBLE (-3425 4525);
FORCEADD ISL99390FRZTR5935..1
(-5825 4150);
FORCEPROP 1 LAST LOCATION PU32
J 0
(-6125 5025);
DISPLAY 0.489362 (-6125 5025);
PAINT SKYBLUE (-6125 5025);
FORCEPROP 2 LAST $SEC 1
J 0
(-6125 5175);
DISPLAY 0.680851 (-6125 5175);
PAINT MONO (-6125 5175);
DISPLAY INVISIBLE (-6125 5175);
FORCEPROP 2 LAST CDS_SEC 1
J 0
(-6125 5175);
DISPLAY 1.021277 (-6125 5175);
DISPLAY INVISIBLE (-6125 5175);
FORCEPROP 2 LASTPIN (-5425 3700) $PN 2
J 0
(-5415 3710);
DISPLAY 0.489362 (-5415 3710);
PAINT MONO (-5415 3710);
FORCEPROP 2 LASTPIN (-5425 4500) $PN 33
J 0
(-5415 4510);
DISPLAY 0.489362 (-5415 4510);
PAINT MONO (-5415 4510);
FORCEPROP 2 LASTPIN (-6275 3900) $PN 31
J 2
(-6285 3910);
DISPLAY 0.489362 (-6285 3910);
PAINT MONO (-6285 3910);
FORCEPROP 2 LASTPIN (-6275 4300) $PN 35
J 2
(-6285 4310);
DISPLAY 0.489362 (-6285 4310);
PAINT MONO (-6285 4310);
FORCEPROP 2 LASTPIN (-5425 3850) $PN 6
J 0
(-5415 3860);
DISPLAY 0.489362 (-5415 3860);
PAINT MONO (-5415 3860);
FORCEPROP 2 LASTPIN (-5425 3800) $PN 41
J 0
(-5415 3810);
DISPLAY 0.489362 (-5415 3810);
PAINT MONO (-5415 3810);
FORCEPROP 2 LASTPIN (-6275 4150) $PN 38
J 2
(-6285 4160);
DISPLAY 0.489362 (-6285 4160);
PAINT MONO (-6285 4160);
FORCEPROP 2 LASTPIN (-6275 3850) $PN 37
J 2
(-6285 3860);
DISPLAY 0.489362 (-6285 3860);
PAINT MONO (-6285 3860);
FORCEPROP 2 LASTPIN (-5425 3650) $PN 5
J 0
(-5415 3660);
DISPLAY 0.489362 (-5415 3660);
PAINT MONO (-5415 3660);
FORCEPROP 2 LASTPIN (-5425 3600) $PN 7_9-20_24
J 0
(-5415 3610);
DISPLAY 0.489362 (-5415 3610);
PAINT MONO (-5415 3610);
FORCEPROP 2 LASTPIN (-5425 3550) $PN 40
J 0
(-5415 3560);
DISPLAY 0.489362 (-5415 3560);
PAINT MONO (-5415 3560);
FORCEPROP 2 LASTPIN (-5425 4250) $PN 32
J 0
(-5415 4260);
DISPLAY 0.489362 (-5415 4260);
PAINT MONO (-5415 4260);
FORCEPROP 2 LASTPIN (-6275 4800) $PN 4
J 2
(-6285 4810);
DISPLAY 0.489362 (-6285 4810);
PAINT MONO (-6285 4810);
FORCEPROP 2 LASTPIN (-6275 3550) $PN 34
J 2
(-6285 3560);
DISPLAY 0.489362 (-6285 3560);
PAINT MONO (-6285 3560);
FORCEPROP 2 LASTPIN (-6275 4050) $PN 39
J 2
(-6285 4060);
DISPLAY 0.489362 (-6285 4060);
PAINT MONO (-6285 4060);
FORCEPROP 2 LASTPIN (-5425 4150) $PN 10_19
J 0
(-5415 4160);
DISPLAY 0.489362 (-5415 4160);
PAINT MONO (-5415 4160);
FORCEPROP 2 LASTPIN (-6275 3650) $PN 36
J 2
(-6285 3660);
DISPLAY 0.489362 (-6285 3660);
PAINT MONO (-6285 3660);
FORCEPROP 2 LASTPIN (-6275 4500) $PN 3
J 2
(-6285 4510);
DISPLAY 0.489362 (-6285 4510);
PAINT MONO (-6285 4510);
FORCEPROP 2 LASTPIN (-5425 4800) $PN 25_29
J 0
(-5415 4810);
DISPLAY 0.489362 (-5415 4810);
PAINT MONO (-5415 4810);
FORCEPROP 2 LASTPIN (-5425 4750) $PN 30
J 0
(-5415 4760);
DISPLAY 0.489362 (-5415 4760);
PAINT MONO (-5415 4760);
FORCEPROP 2 LASTPIN (-5425 3900) $PN 1
J 0
(-5415 3910);
DISPLAY 0.489362 (-5415 3910);
PAINT MONO (-5415 3910);
FORCEPROP 2 LAST PART_TYPE SMLF
J 0
(-6125 5125);
DISPLAY 1.021277 (-6125 5125);
FORCEPROP 1 LAST MATERIAL IC
J 0
(-6125 4875);
DISPLAY 0.489362 (-6125 4875);
PAINT SKYBLUE (-6125 4875);
FORCEPROP 2 LAST VALUE ISL99390FRZ-TR5935
J 0
(-6125 5075);
DISPLAY 0.489362 (-6125 5075);
PAINT SKYBLUE (-6125 5075);
FORCEPROP 1 LAST PART_NUMBER AL099390004
J 0
(-6125 4950);
DISPLAY 0.489362 (-6125 4950);
PAINT SKYBLUE (-6125 4950);
FORCEPROP 2 LAST CDS_LIB pure_quanta
J 0
(-5825 4150);
DISPLAY INVISIBLE (-5825 4150);
FORCEPROP 1 LAST CDS_LMAN_SYM_OUTLINE -300,700,250,-650
J 0
(-5825 4150);
DISPLAY 0.468085 (-5825 4150);
PAINT GREEN (-5825 4150);
DISPLAY INVISIBLE (-5825 4150);
FORCEPROP 1 LAST NEEDS_NO_SIZE TRUE
J 0
(-5825 4150);
DISPLAY 0.723404 (-5825 4150);
PAINT GREEN (-5825 4150);
DISPLAY INVISIBLE (-5825 4150);
FORCEPROP 1 LAST PATH I34
J 0
(-5825 4150);
DISPLAY 0.723404 (-5825 4150);
PAINT GREEN (-5825 4150);
DISPLAY INVISIBLE (-5825 4150);
FORCEADD Q_CAP..1
(-5025 5025);
FORCEPROP 1 LAST LOCATION PC348_3
J 0
(-4975 5125);
DISPLAY 0.489362 (-4975 5125);
PAINT SKYBLUE (-4975 5125);
FORCEPROP 0 LAST $SEC 1
J 0
(-4975 5175);
DISPLAY 0.680851 (-4975 5175);
PAINT MONO (-4975 5175);
DISPLAY INVISIBLE (-4975 5175);
FORCEPROP 0 LAST CDS_SEC 1
J 0
(-4975 5175);
DISPLAY 1.021277 (-4975 5175);
DISPLAY INVISIBLE (-4975 5175);
FORCEPROP 1 LASTPIN (-5025 5125) $PN 1
J 0
(-5015 5105);
DISPLAY 0.489362 (-5015 5105);
PAINT MONO (-5015 5105);
FORCEPROP 1 LASTPIN (-5025 4925) $PN 2
J 0
(-5015 4905);
DISPLAY 0.489362 (-5015 4905);
PAINT MONO (-5015 4905);
FORCEPROP 1 LAST MATERIAL X7R
J 0
(-4975 4925);
DISPLAY 0.489362 (-4975 4925);
PAINT SKYBLUE (-4975 4925);
FORCEPROP 1 LAST TOLERANCE 10%
J 0
(-4975 4975);
DISPLAY 0.489362 (-4975 4975);
PAINT SKYBLUE (-4975 4975);
FORCEPROP 1 LAST VALUE 0.1UF
J 0
(-4975 5075);
DISPLAY 0.489362 (-4975 5075);
PAINT SKYBLUE (-4975 5075);
FORCEPROP 1 LAST PART_NUMBER CH4104K1B00
J 0
(-4975 4875);
DISPLAY 0.489362 (-4975 4875);
PAINT SKYBLUE (-4975 4875);
FORCEPROP 1 LAST VOLTAGE 25V
J 0
(-4975 5025);
DISPLAY 0.489362 (-4975 5025);
PAINT SKYBLUE (-4975 5025);
FORCEPROP 1 LAST PACK_TYPE 0402
J 0
(-4975 4825);
DISPLAY 0.489362 (-4975 4825);
PAINT SKYBLUE (-4975 4825);
FORCEPROP 2 LAST CDS_LIB pure_quanta
J 0
(-5025 5025);
DISPLAY INVISIBLE (-5025 5025);
FORCEPROP 1 LAST PATH I37
J 0
(-4975 5175);
DISPLAY 0.978723 (-4975 5175);
PAINT WHITE (-4975 5175);
DISPLAY INVISIBLE (-4975 5175);
FORCEADD Q_CAP..1
(-7325 4500);
FORCEPROP 1 LAST LOCATION PC346
J 0
(-7275 4600);
DISPLAY 0.489362 (-7275 4600);
PAINT SKYBLUE (-7275 4600);
FORCEPROP 0 LAST $SEC 1
J 0
(-7275 4650);
DISPLAY 0.680851 (-7275 4650);
PAINT MONO (-7275 4650);
DISPLAY INVISIBLE (-7275 4650);
FORCEPROP 0 LAST CDS_SEC 1
J 0
(-7275 4650);
DISPLAY 1.021277 (-7275 4650);
DISPLAY INVISIBLE (-7275 4650);
FORCEPROP 1 LASTPIN (-7325 4600) $PN 1
J 0
(-7315 4580);
DISPLAY 0.489362 (-7315 4580);
PAINT MONO (-7315 4580);
FORCEPROP 1 LASTPIN (-7325 4400) $PN 2
J 0
(-7315 4380);
DISPLAY 0.489362 (-7315 4380);
PAINT MONO (-7315 4380);
FORCEPROP 1 LAST MATERIAL X6S
J 0
(-7275 4400);
DISPLAY 0.489362 (-7275 4400);
PAINT SKYBLUE (-7275 4400);
FORCEPROP 1 LAST TOLERANCE 10%
J 0
(-7275 4450);
DISPLAY 0.489362 (-7275 4450);
PAINT SKYBLUE (-7275 4450);
FORCEPROP 1 LAST VALUE 2.2UF
J 0
(-7275 4550);
DISPLAY 0.489362 (-7275 4550);
PAINT SKYBLUE (-7275 4550);
FORCEPROP 1 LAST PART_NUMBER CH5222KEB01
J 0
(-7275 4350);
DISPLAY 0.489362 (-7275 4350);
PAINT SKYBLUE (-7275 4350);
FORCEPROP 1 LAST VOLTAGE 10V
J 0
(-7275 4500);
DISPLAY 0.489362 (-7275 4500);
PAINT SKYBLUE (-7275 4500);
FORCEPROP 1 LAST PACK_TYPE C0402
J 0
(-7275 4300);
DISPLAY 0.489362 (-7275 4300);
PAINT SKYBLUE (-7275 4300);
FORCEPROP 2 LAST CDS_LIB pure_quanta
J 0
(-7325 4500);
DISPLAY INVISIBLE (-7325 4500);
FORCEPROP 1 LAST PATH I38
J 0
(-7275 4650);
DISPLAY 0.978723 (-7275 4650);
PAINT WHITE (-7275 4650);
DISPLAY INVISIBLE (-7275 4650);
FORCEADD UNIVERSAL_GND..1
(-7325 4300);
FORCEPROP 3 LASTPIN (-7325 4350) SIG_NAME GND\g
J 0
(-7315 4360);
DISPLAY 0.659574 (-7315 4360);
PAINT MONO (-7315 4360);
DISPLAY INVISIBLE (-7315 4360);
FORCEPROP 2 LAST CDS_LIB pure_quanta_power
J 0
(-7325 4300);
DISPLAY INVISIBLE (-7325 4300);
FORCEPROP 1 LAST PATH I39
J 0
(-7250 4300);
DISPLAY 0.872340 (-7250 4300);
PAINT AQUA (-7250 4300);
DISPLAY INVISIBLE (-7250 4300);
FORCEPROP 1 LAST HDL_POWER GND
J 1
(-7300 4225);
DISPLAY 0.872340 (-7300 4225);
PAINT GREEN (-7300 4225);
DISPLAY INVISIBLE (-7300 4225);
FORCEADD OFFPAGE..2
R 2
(-6950 3650);
FORCEPROP 2 LAST $XR1 186 
J 0
(-7235 3614);
DISPLAY 0.638298 (-7235 3614);
PAINT MONO (-7235 3614);
FORCEPROP 2 LAST $XR0 191 
J 0
(-7235 3650);
DISPLAY 0.638298 (-7235 3650);
PAINT MONO (-7235 3650);
FORCEPROP 2 LAST PATH I4
J 0
(-6900 3725);
DISPLAY 1.021277 (-6900 3725);
DISPLAY INVISIBLE (-6900 3725);
FORCEPROP 1 LAST COMMENT_BODY TRUE
J 2
(-6905 3555);
DISPLAY 0.872340 (-6905 3555);
PAINT GREEN (-6905 3555);
DISPLAY INVISIBLE (-6905 3555);
FORCEPROP 1 LAST OFFPAGE TRUE
J 2
(-7275 3525);
DISPLAY 0.872340 (-7275 3525);
PAINT GREEN (-7275 3525);
DISPLAY INVISIBLE (-7275 3525);
FORCEPROP 2 LAST CDS_LIB standard
J 0
(-6950 3650);
DISPLAY INVISIBLE (-6950 3650);
FORCEADD UNIVERSAL_GND..1
(-6975 4800);
FORCEPROP 3 LASTPIN (-6975 4850) SIG_NAME GND\g
J 0
(-6965 4860);
DISPLAY 0.659574 (-6965 4860);
PAINT MONO (-6965 4860);
DISPLAY INVISIBLE (-6965 4860);
FORCEPROP 2 LAST CDS_LIB pure_quanta_power
J 0
(-6975 4800);
DISPLAY INVISIBLE (-6975 4800);
FORCEPROP 1 LAST PATH I40
J 0
(-6900 4800);
DISPLAY 0.872340 (-6900 4800);
PAINT AQUA (-6900 4800);
DISPLAY INVISIBLE (-6900 4800);
FORCEPROP 1 LAST HDL_POWER GND
J 1
(-6950 4725);
DISPLAY 0.872340 (-6950 4725);
PAINT GREEN (-6950 4725);
DISPLAY INVISIBLE (-6950 4725);
FORCEADD Q_RES..2
(-7325 5050);
FORCEPROP 1 LAST LOCATION PR213
J 0
(-7280 5175);
DISPLAY 0.489362 (-7280 5175);
PAINT SKYBLUE (-7280 5175);
FORCEPROP 0 LAST $SEC 1
J 0
(-7275 5225);
DISPLAY 0.680851 (-7275 5225);
PAINT MONO (-7275 5225);
DISPLAY INVISIBLE (-7275 5225);
FORCEPROP 0 LAST CDS_SEC 1
J 0
(-7275 5225);
DISPLAY 1.021277 (-7275 5225);
DISPLAY INVISIBLE (-7275 5225);
FORCEPROP 1 LASTPIN (-7325 5150) $PN 1
J 0
(-7320 5112);
DISPLAY 0.489362 (-7320 5112);
PAINT MONO (-7320 5112);
FORCEPROP 1 LASTPIN (-7325 4950) $PN 2
J 0
(-7320 4960);
DISPLAY 0.489362 (-7320 4960);
PAINT MONO (-7320 4960);
FORCEPROP 1 LAST WATTAGE 1/16W
J 0
(-7275 5025);
DISPLAY 0.489362 (-7275 5025);
PAINT SKYBLUE (-7275 5025);
FORCEPROP 1 LAST MATERIAL CHIP
J 0
(-7275 4975);
DISPLAY 0.489362 (-7275 4975);
PAINT SKYBLUE (-7275 4975);
FORCEPROP 1 LAST TOLERANCE 1%
J 0
(-7275 5075);
DISPLAY 0.489362 (-7275 5075);
PAINT SKYBLUE (-7275 5075);
FORCEPROP 1 LAST VALUE 2.2
J 0
(-7275 5125);
DISPLAY 0.489362 (-7275 5125);
PAINT SKYBLUE (-7275 5125);
FORCEPROP 1 LAST PART_NUMBER CS-2202FB00
J 0
(-7275 4925);
DISPLAY 0.489362 (-7275 4925);
PAINT SKYBLUE (-7275 4925);
FORCEPROP 1 LAST PACK_TYPE 0402LF
J 0
(-7275 4875);
DISPLAY 0.489362 (-7275 4875);
PAINT SKYBLUE (-7275 4875);
FORCEPROP 2 LAST CDS_LIB pure_quanta
J 0
(-7325 5050);
DISPLAY INVISIBLE (-7325 5050);
FORCEPROP 1 LAST PATH I41
J 0
(-7275 5225);
DISPLAY 0.978723 (-7275 5225);
PAINT WHITE (-7275 5225);
DISPLAY INVISIBLE (-7275 5225);
FORCEADD Q_CAP..1
(-6975 5075);
FORCEPROP 1 LAST LOCATION PC347_SOP1_3
J 0
(-6925 5175);
DISPLAY 0.489362 (-6925 5175);
PAINT SKYBLUE (-6925 5175);
FORCEPROP 0 LAST $SEC 1
J 0
(-6925 5225);
DISPLAY 0.680851 (-6925 5225);
PAINT MONO (-6925 5225);
DISPLAY INVISIBLE (-6925 5225);
FORCEPROP 0 LAST CDS_SEC 1
J 0
(-6925 5225);
DISPLAY 1.021277 (-6925 5225);
DISPLAY INVISIBLE (-6925 5225);
FORCEPROP 1 LASTPIN (-6975 5175) $PN 1
J 0
(-6965 5155);
DISPLAY 0.489362 (-6965 5155);
PAINT MONO (-6965 5155);
FORCEPROP 1 LASTPIN (-6975 4975) $PN 2
J 0
(-6965 4955);
DISPLAY 0.489362 (-6965 4955);
PAINT MONO (-6965 4955);
FORCEPROP 1 LAST MATERIAL X6S
J 0
(-6925 4975);
DISPLAY 0.489362 (-6925 4975);
PAINT SKYBLUE (-6925 4975);
FORCEPROP 1 LAST TOLERANCE 10%
J 0
(-6925 5025);
DISPLAY 0.489362 (-6925 5025);
PAINT SKYBLUE (-6925 5025);
FORCEPROP 1 LAST VALUE 2.2UF
J 0
(-6925 5125);
DISPLAY 0.489362 (-6925 5125);
PAINT SKYBLUE (-6925 5125);
FORCEPROP 1 LAST PART_NUMBER CH5222KEB01
J 0
(-6925 4925);
DISPLAY 0.489362 (-6925 4925);
PAINT SKYBLUE (-6925 4925);
FORCEPROP 1 LAST VOLTAGE 10V
J 0
(-6925 5075);
DISPLAY 0.489362 (-6925 5075);
PAINT SKYBLUE (-6925 5075);
FORCEPROP 1 LAST PACK_TYPE C0402
J 0
(-6925 4875);
DISPLAY 0.489362 (-6925 4875);
PAINT SKYBLUE (-6925 4875);
FORCEPROP 2 LAST CDS_LIB pure_quanta
J 0
(-6975 5075);
DISPLAY INVISIBLE (-6975 5075);
FORCEPROP 1 LAST PATH I42
J 0
(-6925 5225);
DISPLAY 0.978723 (-6925 5225);
PAINT WHITE (-6925 5225);
DISPLAY INVISIBLE (-6925 5225);
FORCEADD VCC_CORE..1
(-7325 5450);
FORCEPROP 3 LASTPIN (-7325 5400) SIG_NAME PVDDCR_CPU0_P1_PVCC\g
J 0
(-7315 5410);
DISPLAY 0.659574 (-7315 5410);
PAINT MONO (-7315 5410);
DISPLAY INVISIBLE (-7315 5410);
FORCEPROP 1 LAST HDL_POWER PVDDCR_CPU0_P1_PVCC
J 1
(-7325 5500);
DISPLAY 0.489362 (-7325 5500);
PAINT GREEN (-7325 5500);
FORCEPROP 2 LAST CDS_LIB pure_quanta_power
J 0
(-7325 5450);
DISPLAY INVISIBLE (-7325 5450);
FORCEPROP 1 LAST PATH I43
J 0
(-7275 5475);
DISPLAY 0.872340 (-7275 5475);
PAINT AQUA (-7275 5475);
DISPLAY INVISIBLE (-7275 5475);
FORCEADD UNIVERSAL_GND..1
(-4425 3200);
FORCEPROP 3 LASTPIN (-4425 3250) SIG_NAME GND\g
J 0
(-4415 3260);
DISPLAY 0.659574 (-4415 3260);
PAINT MONO (-4415 3260);
DISPLAY INVISIBLE (-4415 3260);
FORCEPROP 2 LAST CDS_LIB pure_quanta_power
J 0
(-4425 3200);
DISPLAY INVISIBLE (-4425 3200);
FORCEPROP 1 LAST PATH I45
J 0
(-4350 3200);
DISPLAY 0.872340 (-4350 3200);
PAINT AQUA (-4350 3200);
DISPLAY INVISIBLE (-4350 3200);
FORCEPROP 1 LAST HDL_POWER GND
J 1
(-4400 3125);
DISPLAY 0.872340 (-4400 3125);
PAINT GREEN (-4400 3125);
DISPLAY INVISIBLE (-4400 3125);
FORCEADD Q_RES..2
(-4425 3425);
FORCEPROP 1 LAST LOCATION PR511
J 0
(-4380 3550);
DISPLAY 0.489362 (-4380 3550);
PAINT SKYBLUE (-4380 3550);
FORCEPROP 0 LAST $SEC 1
J 0
(-4375 3600);
DISPLAY 0.680851 (-4375 3600);
PAINT MONO (-4375 3600);
DISPLAY INVISIBLE (-4375 3600);
FORCEPROP 0 LAST CDS_SEC 1
J 0
(-4375 3600);
DISPLAY 1.021277 (-4375 3600);
DISPLAY INVISIBLE (-4375 3600);
FORCEPROP 1 LASTPIN (-4425 3525) $PN 1
J 0
(-4420 3487);
DISPLAY 0.489362 (-4420 3487);
PAINT MONO (-4420 3487);
FORCEPROP 1 LASTPIN (-4425 3325) $PN 2
J 0
(-4420 3335);
DISPLAY 0.489362 (-4420 3335);
PAINT MONO (-4420 3335);
FORCEPROP 1 LAST WATTAGE 1/8W
J 0
(-4385 3400);
DISPLAY 0.489362 (-4385 3400);
PAINT SKYBLUE (-4385 3400);
FORCEPROP 1 LAST MATERIAL EMPTY
J 0
(-4385 3350);
DISPLAY 0.489362 (-4385 3350);
PAINT RED (-4385 3350);
FORCEPROP 1 LAST TOLERANCE 1%
J 0
(-4380 3450);
DISPLAY 0.489362 (-4380 3450);
PAINT SKYBLUE (-4380 3450);
FORCEPROP 1 LAST VALUE 1.5
J 0
(-4380 3500);
DISPLAY 0.489362 (-4380 3500);
PAINT SKYBLUE (-4380 3500);
FORCEPROP 1 LAST PART_NUMBER CS-1504FB00
J 0
(-4385 3300);
DISPLAY 0.489362 (-4385 3300);
PAINT SKYBLUE (-4385 3300);
FORCEPROP 1 LAST PACK_TYPE 0402LF
J 0
(-4385 3250);
DISPLAY 0.489362 (-4385 3250);
PAINT SKYBLUE (-4385 3250);
FORCEPROP 2 LAST CDS_LIB pure_quanta
J 0
(-4425 3425);
DISPLAY INVISIBLE (-4425 3425);
FORCEPROP 1 LAST PATH I46
J 0
(-4375 3600);
DISPLAY 0.978723 (-4375 3600);
PAINT WHITE (-4375 3600);
DISPLAY INVISIBLE (-4375 3600);
FORCEADD Q_CAP..1
(-4425 3950);
FORCEPROP 1 LAST LOCATION PC195
J 0
(-4375 4050);
DISPLAY 0.489362 (-4375 4050);
PAINT SKYBLUE (-4375 4050);
FORCEPROP 0 LAST $SEC 1
J 0
(-4375 4100);
DISPLAY 0.680851 (-4375 4100);
PAINT MONO (-4375 4100);
DISPLAY INVISIBLE (-4375 4100);
FORCEPROP 0 LAST CDS_SEC 1
J 0
(-4375 4100);
DISPLAY 1.021277 (-4375 4100);
DISPLAY INVISIBLE (-4375 4100);
FORCEPROP 1 LASTPIN (-4425 4050) $PN 1
J 0
(-4415 4030);
DISPLAY 0.489362 (-4415 4030);
PAINT MONO (-4415 4030);
FORCEPROP 1 LASTPIN (-4425 3850) $PN 2
J 0
(-4415 3830);
DISPLAY 0.489362 (-4415 3830);
PAINT MONO (-4415 3830);
FORCEPROP 1 LAST MATERIAL EMPTY
J 0
(-4375 3850);
DISPLAY 0.489362 (-4375 3850);
PAINT RED (-4375 3850);
FORCEPROP 1 LAST TOLERANCE 10%
J 0
(-4375 3900);
DISPLAY 0.489362 (-4375 3900);
PAINT SKYBLUE (-4375 3900);
FORCEPROP 1 LAST VALUE 560PF
J 0
(-4375 4000);
DISPLAY 0.489362 (-4375 4000);
PAINT SKYBLUE (-4375 4000);
FORCEPROP 1 LAST VOLTAGE 50V
J 0
(-4375 3950);
DISPLAY 0.489362 (-4375 3950);
PAINT SKYBLUE (-4375 3950);
FORCEPROP 1 LAST PACK_TYPE C0402
J 0
(-4375 3750);
DISPLAY 0.489362 (-4375 3750);
PAINT SKYBLUE (-4375 3750);
FORCEPROP 1 LAST PART_NUMBER CH1566K1B09
J 0
(-4375 3800);
DISPLAY 0.489362 (-4375 3800);
PAINT SKYBLUE (-4375 3800);
FORCEPROP 2 LAST CDS_LIB pure_quanta
J 0
(-4425 3950);
DISPLAY INVISIBLE (-4425 3950);
FORCEPROP 1 LAST PATH I47
J 0
(-4375 4100);
DISPLAY 0.978723 (-4375 4100);
PAINT WHITE (-4375 4100);
DISPLAY INVISIBLE (-4375 4100);
FORCEADD Q_CAP..1
(-3300 5025);
FORCEPROP 1 LAST LOCATION PC353_3
J 0
(-3250 5125);
DISPLAY 0.489362 (-3250 5125);
PAINT SKYBLUE (-3250 5125);
FORCEPROP 0 LAST $SEC 1
J 0
(-3250 5150);
DISPLAY 0.680851 (-3250 5150);
PAINT MONO (-3250 5150);
DISPLAY INVISIBLE (-3250 5150);
FORCEPROP 0 LAST CDS_SEC 1
J 0
(-3250 5150);
DISPLAY 0.680851 (-3250 5150);
DISPLAY INVISIBLE (-3250 5150);
FORCEPROP 1 LASTPIN (-3300 5125) $PN 1
J 0
(-3290 5105);
DISPLAY 0.787234 (-3290 5105);
PAINT MONO (-3290 5105);
DISPLAY INVISIBLE (-3290 5105);
FORCEPROP 1 LASTPIN (-3300 4925) $PN 2
J 0
(-3290 4905);
DISPLAY 0.787234 (-3290 4905);
PAINT MONO (-3290 4905);
DISPLAY INVISIBLE (-3290 4905);
FORCEPROP 1 LAST MATERIAL X6S
J 0
(-3250 4925);
DISPLAY 0.489362 (-3250 4925);
PAINT SKYBLUE (-3250 4925);
FORCEPROP 1 LAST TOLERANCE 10%
J 0
(-3250 4975);
DISPLAY 0.489362 (-3250 4975);
PAINT SKYBLUE (-3250 4975);
FORCEPROP 1 LAST VALUE 10UF
J 0
(-3250 5075);
DISPLAY 0.489362 (-3250 5075);
PAINT SKYBLUE (-3250 5075);
FORCEPROP 1 LAST PART_NUMBER CH6104KEA00
J 0
(-3250 4875);
DISPLAY 0.489362 (-3250 4875);
PAINT SKYBLUE (-3250 4875);
FORCEPROP 1 LAST VOLTAGE 25V
J 0
(-3250 5025);
DISPLAY 0.489362 (-3250 5025);
PAINT SKYBLUE (-3250 5025);
FORCEPROP 1 LAST PACK_TYPE C0805
J 0
(-3250 4825);
DISPLAY 0.489362 (-3250 4825);
PAINT SKYBLUE (-3250 4825);
FORCEPROP 2 LAST CDS_LIB pure_quanta
J 0
(-3300 5025);
DISPLAY INVISIBLE (-3300 5025);
FORCEPROP 1 LAST PATH I48
J 0
(-3250 5175);
DISPLAY 0.978723 (-3250 5175);
PAINT WHITE (-3250 5175);
DISPLAY INVISIBLE (-3250 5175);
FORCEADD OFFPAGE..1
(-6925 3550);
FORCEPROP 2 LAST $XR0 186 
J 0
(-7207 3550);
DISPLAY 0.638298 (-7207 3550);
PAINT MONO (-7207 3550);
FORCEPROP 2 LAST PATH I5
J 0
(-6875 3625);
DISPLAY 1.021277 (-6875 3625);
DISPLAY INVISIBLE (-6875 3625);
FORCEPROP 1 LAST COMMENT_BODY TRUE
J 0
(-6800 3450);
DISPLAY 0.872340 (-6800 3450);
PAINT GREEN (-6800 3450);
DISPLAY INVISIBLE (-6800 3450);
FORCEPROP 1 LAST OFFPAGE TRUE
J 0
(-6600 3425);
DISPLAY 0.872340 (-6600 3425);
PAINT GREEN (-6600 3425);
DISPLAY INVISIBLE (-6600 3425);
FORCEPROP 2 LAST CDS_LIB standard
J 2
(-6925 3550);
DISPLAY INVISIBLE (-6925 3550);
FORCEADD OFFPAGE..3
(-1825 3900);
FORCEPROP 2 LAST $XR0 191 
J 0
(-1611 3900);
DISPLAY 0.638298 (-1611 3900);
PAINT MONO (-1611 3900);
FORCEPROP 1 LAST COMMENT_BODY TRUE
J 0
(-1875 3800);
DISPLAY 0.872340 (-1875 3800);
PAINT GREEN (-1875 3800);
DISPLAY INVISIBLE (-1875 3800);
FORCEPROP 1 LAST OFFPAGE TRUE
J 0
(-1500 3775);
DISPLAY 0.872340 (-1500 3775);
PAINT GREEN (-1500 3775);
DISPLAY INVISIBLE (-1500 3775);
FORCEPROP 2 LAST CDS_LIB standard
J 2
(-1825 3900);
DISPLAY INVISIBLE (-1825 3900);
FORCEPROP 2 LAST PATH I51
J 0
(-1600 3925);
DISPLAY 1.021277 (-1600 3925);
DISPLAY INVISIBLE (-1600 3925);
FORCEADD Q_INDUCTOR..1
(-3625 3925);
FORCEPROP 1 LAST LOCATION PL34
J 0
(-3775 4075);
DISPLAY 0.574468 (-3775 4075);
PAINT SKYBLUE (-3775 4075);
FORCEPROP 0 LAST $SEC 1
J 0
(-3775 4125);
DISPLAY 0.680851 (-3775 4125);
PAINT MONO (-3775 4125);
DISPLAY INVISIBLE (-3775 4125);
FORCEPROP 0 LAST CDS_SEC 1
J 0
(-3775 4100);
DISPLAY 1.021277 (-3775 4100);
DISPLAY INVISIBLE (-3775 4100);
FORCEPROP 0 LASTPIN (-3725 3900) $PN 1
J 2
(-3735 3910);
DISPLAY 0.680851 (-3735 3910);
PAINT MONO (-3735 3910);
FORCEPROP 0 LASTPIN (-3525 3900) $PN 2
J 0
(-3515 3910);
DISPLAY 0.680851 (-3515 3910);
PAINT MONO (-3515 3910);
FORCEPROP 1 LAST PART_NUMBER CV+22Y0EZ00
J 0
(-3775 3975);
DISPLAY 0.468085 (-3775 3975);
PAINT SKYBLUE (-3775 3975);
FORCEPROP 2 LAST VALUE 0.22UH/33A
J 0
(-3775 4000);
DISPLAY 0.489362 (-3775 4000);
PAINT SKYBLUE (-3775 4000);
FORCEPROP 2 LAST PACK_TYPE SMLF
J 0
(-3775 4025);
DISPLAY 0.617021 (-3775 4025);
FORCEPROP 1 LAST MATERIAL IND
J 0
(-3775 3950);
DISPLAY 0.468085 (-3775 3950);
PAINT SKYBLUE (-3775 3950);
FORCEPROP 1 LAST NEEDS_NO_SIZE TRUE
J 0
(-3625 3925);
DISPLAY 0.468085 (-3625 3925);
PAINT GREEN (-3625 3925);
DISPLAY INVISIBLE (-3625 3925);
FORCEPROP 1 LAST PATH I52
J 0
(-3550 3980);
DISPLAY 0.723404 (-3550 3980);
PAINT GREEN (-3550 3980);
DISPLAY INVISIBLE (-3550 3980);
FORCEPROP 2 LAST CDS_LIB pure_quanta
J 0
(-3625 3925);
DISPLAY INVISIBLE (-3625 3925);
FORCEADD UNIVERSAL_GND..1
(-3800 3800);
FORCEPROP 3 LASTPIN (-3800 3850) SIG_NAME GND\g
J 0
(-3790 3860);
DISPLAY 0.659574 (-3790 3860);
PAINT MONO (-3790 3860);
DISPLAY INVISIBLE (-3790 3860);
FORCEPROP 2 LAST CDS_LIB pure_quanta_power
J 0
(-3800 3800);
DISPLAY INVISIBLE (-3800 3800);
FORCEPROP 1 LAST PATH I53
J 0
(-3725 3800);
DISPLAY 0.872340 (-3725 3800);
PAINT AQUA (-3725 3800);
DISPLAY INVISIBLE (-3725 3800);
FORCEPROP 1 LAST HDL_POWER GND
J 1
(-3775 3725);
DISPLAY 0.872340 (-3775 3725);
PAINT GREEN (-3775 3725);
DISPLAY INVISIBLE (-3775 3725);
FORCEADD Q_CAP..1
(-7650 3875);
FORCEPROP 1 LAST LOCATION PC345_9
J 0
(-7600 3975);
DISPLAY 0.489362 (-7600 3975);
PAINT SKYBLUE (-7600 3975);
FORCEPROP 0 LAST $SEC 1
J 0
(-7600 4000);
DISPLAY 0.680851 (-7600 4000);
PAINT MONO (-7600 4000);
DISPLAY INVISIBLE (-7600 4000);
FORCEPROP 0 LAST CDS_SEC 1
J 0
(-7600 4000);
DISPLAY 1.021277 (-7600 4000);
DISPLAY INVISIBLE (-7600 4000);
FORCEPROP 1 LASTPIN (-7650 3975) $PN 1
J 0
(-7640 3955);
DISPLAY 0.489362 (-7640 3955);
PAINT MONO (-7640 3955);
FORCEPROP 1 LASTPIN (-7650 3775) $PN 2
J 0
(-7640 3755);
DISPLAY 0.489362 (-7640 3755);
PAINT MONO (-7640 3755);
FORCEPROP 1 LAST MATERIAL X7R
J 0
(-7600 3775);
DISPLAY 0.489362 (-7600 3775);
PAINT SKYBLUE (-7600 3775);
FORCEPROP 1 LAST TOLERANCE 10%
J 0
(-7600 3825);
DISPLAY 0.489362 (-7600 3825);
PAINT SKYBLUE (-7600 3825);
FORCEPROP 1 LAST VALUE 0.1UF
J 0
(-7600 3925);
DISPLAY 0.489362 (-7600 3925);
PAINT SKYBLUE (-7600 3925);
FORCEPROP 1 LAST PART_NUMBER CH4104K1B00
J 0
(-7600 3725);
DISPLAY 0.489362 (-7600 3725);
PAINT SKYBLUE (-7600 3725);
FORCEPROP 1 LAST VOLTAGE 25V
J 0
(-7600 3875);
DISPLAY 0.489362 (-7600 3875);
PAINT SKYBLUE (-7600 3875);
FORCEPROP 1 LAST PACK_TYPE 0402
J 0
(-7600 3675);
DISPLAY 0.489362 (-7600 3675);
PAINT SKYBLUE (-7600 3675);
FORCEPROP 2 LAST CDS_LIB pure_quanta
J 0
(-7650 3875);
DISPLAY INVISIBLE (-7650 3875);
FORCEPROP 1 LAST PATH I6
J 0
(-7600 4025);
DISPLAY 0.978723 (-7600 4025);
PAINT WHITE (-7600 4025);
DISPLAY INVISIBLE (-7600 4025);
FORCEADD Q_RES..1
(-6975 3850);
FORCEPROP 1 LAST LOCATION PR214
J 0
(-7025 3900);
DISPLAY 0.489362 (-7025 3900);
PAINT SKYBLUE (-7025 3900);
FORCEPROP 0 LAST $SEC 1
J 0
(-6975 3925);
DISPLAY 0.680851 (-6975 3925);
PAINT MONO (-6975 3925);
DISPLAY INVISIBLE (-6975 3925);
FORCEPROP 0 LAST CDS_SEC 1
J 0
(-6975 3925);
DISPLAY 1.021277 (-6975 3925);
DISPLAY INVISIBLE (-6975 3925);
FORCEPROP 1 LASTPIN (-7075 3850) $PN 1
J 0
(-7063 3862);
DISPLAY 0.489362 (-7063 3862);
PAINT MONO (-7063 3862);
FORCEPROP 1 LASTPIN (-6875 3850) $PN 2
J 0
(-6913 3862);
DISPLAY 0.489362 (-6913 3862);
PAINT MONO (-6913 3862);
FORCEPROP 1 LAST WATTAGE 1/16W
J 0
(-6875 3750);
DISPLAY 0.489362 (-6875 3750);
PAINT SKYBLUE (-6875 3750);
FORCEPROP 1 LAST MATERIAL EMPTY
J 0
(-7275 3750);
DISPLAY 0.489362 (-7275 3750);
PAINT RED (-7275 3750);
FORCEPROP 1 LAST TOLERANCE 1%
J 0
(-6850 3875);
DISPLAY 0.489362 (-6850 3875);
PAINT SKYBLUE (-6850 3875);
FORCEPROP 1 LAST VALUE 8.87K
J 2
(-7100 3875);
DISPLAY 0.489362 (-7100 3875);
PAINT SKYBLUE (-7100 3875);
FORCEPROP 1 LAST PART_NUMBER CS28872FB01
J 0
(-7275 3800);
DISPLAY 0.489362 (-7275 3800);
PAINT SKYBLUE (-7275 3800);
FORCEPROP 1 LAST PACK_TYPE 0402LF
J 0
(-6875 3800);
DISPLAY 0.489362 (-6875 3800);
PAINT SKYBLUE (-6875 3800);
FORCEPROP 2 LAST CDS_LIB pure_quanta
J 0
(-6975 3850);
DISPLAY INVISIBLE (-6975 3850);
FORCEPROP 1 LAST PATH I7
J 0
(-7025 4000);
DISPLAY 0.978723 (-7025 4000);
PAINT WHITE (-7025 4000);
DISPLAY INVISIBLE (-7025 4000);
FORCEADD OFFPAGE..2
R 2
(-6975 4150);
FORCEPROP 2 LAST $XR0 186 
J 0
(-7230 4150);
DISPLAY 0.638298 (-7230 4150);
PAINT MONO (-7230 4150);
FORCEPROP 2 LAST PATH I8
J 0
(-6925 4225);
DISPLAY 1.021277 (-6925 4225);
DISPLAY INVISIBLE (-6925 4225);
FORCEPROP 1 LAST COMMENT_BODY TRUE
J 2
(-6930 4055);
DISPLAY 0.872340 (-6930 4055);
PAINT GREEN (-6930 4055);
DISPLAY INVISIBLE (-6930 4055);
FORCEPROP 1 LAST OFFPAGE TRUE
J 2
(-7300 4025);
DISPLAY 0.872340 (-7300 4025);
PAINT GREEN (-7300 4025);
DISPLAY INVISIBLE (-7300 4025);
FORCEPROP 2 LAST CDS_LIB standard
J 2
(-6975 4150);
DISPLAY INVISIBLE (-6975 4150);
FORCEADD QUANTA_TITLE_BLOCK_C..1
(0 0);
FORCEPROP 0 LAST CDS_CON_LAST_MODIFIED Fri Mar 11 14:53:34 2022
J 0
(-1885 15);
DISPLAY INVISIBLE (-1885 15);
FORCEPROP 1 LAST CUSTOM_TXT_CDS <CON_LAST_MODIFIED>
J 0
(-1885 15);
DISPLAY 0.978723 (-1885 15);
FORCEPROP 2 LAST CUSTOM_TXT_CDS <XR_PAGE_TITLE>
J 0
(-7890 5250);
DISPLAY 0.638298 (-7890 5250);
PAINT PINK (-7890 5250);
DISPLAY INVISIBLE (-7890 5250);
FORCEPROP 1 LAST CUSTOM_TXT_CDS <NAME_2>
J 0
(-3175 50);
FORCEPROP 1 LAST CUSTOM_TXT_CDS <NAME_1>
J 0
(-3175 175);
FORCEPROP 1 LAST CUSTOM_TXT_CDS <Q_NUMBER>
J 0
(-1403 103);
DISPLAY 1.212766 (-1403 103);
FORCEPROP 1 LAST CUSTOM_TXT_CDS <Q_PROJ>
J 0
(-2382 102);
DISPLAY 1.212766 (-2382 102);
FORCEPROP 1 LAST CUSTOM_TXT_CDS <Q_REV>
J 0
(-184 103);
DISPLAY 1.212766 (-184 103);
FORCEPROP 1 LAST CUSTOM_TXT_CDS <CON_PAGE_NUM> OF <CON_TOTAL_PAGES>
J 0
(-446 18);
DISPLAY 0.978723 (-446 18);
FORCEPROP 1 LAST Q_TITLE PVDDCR_SOC_P1 VR PHASE 3
J 0
(-9325 50);
DISPLAY 2.446809 (-9325 50);
PAINT GREEN (-9325 50);
FORCEPROP 1 LAST Q_DEPT BU9
J 1
(-3763 49);
DISPLAY 1.957447 (-3763 49);
PAINT GREEN (-3763 49);
FORCEPROP 1 LAST CDS_LMAN_SYM_OUTLINE -9475,6775,100,-125
J 0
(0 0);
DISPLAY 0.468085 (0 0);
PAINT GREEN (0 0);
DISPLAY INVISIBLE (0 0);
FORCEPROP 2 LAST CDS_LIB pure_quanta
J 0
(0 0);
DISPLAY INVISIBLE (0 0);
FORCEPROP 2 LAST PAGE_BORDER TRUE
J 0
(-7890 5250);
DISPLAY 0.638298 (-7890 5250);
PAINT PINK (-7890 5250);
DISPLAY INVISIBLE (-7890 5250);
FORCEPROP 1 LAST COMMENT_BODY TRUE
J 0
(12 -13);
DISPLAY 0.978723 (12 -13);
PAINT GREEN (12 -13);
DISPLAY INVISIBLE (12 -13);
FORCEPROP 2 LAST CDS_XR_PAGE_TITLE CR-192 : @T6G_MB_LIB.T6G(SCH_1):PAGE192
J 0
(-7890 5250);
DISPLAY 0.638298 (-7890 5250);
PAINT PINK (-7890 5250);
DISPLAY INVISIBLE (-7890 5250);
FORCEADD DNS..1
(-4450 3950);
PAINT RED (-4450 3950);
FORCEPROP 2 LAST CDS_LIB mstr_misc
J 0
(-4450 3950);
DISPLAY INVISIBLE (-4450 3950);
FORCEPROP 1 LAST COMMENT_BODY TRUE
R 1
J 0
(-4375 3725);
DISPLAY 0.872340 (-4375 3725);
PAINT GREEN (-4375 3725);
DISPLAY INVISIBLE (-4375 3725);
FORCEADD DNS..1
(-6975 3825);
PAINT RED (-6975 3825);
FORCEPROP 2 LAST CDS_LIB mstr_misc
J 0
(-6975 3825);
DISPLAY INVISIBLE (-6975 3825);
FORCEPROP 1 LAST COMMENT_BODY TRUE
R 1
J 0
(-6900 3600);
DISPLAY 0.872340 (-6900 3600);
PAINT GREEN (-6900 3600);
DISPLAY INVISIBLE (-6900 3600);
FORCEADD DNS..1
(-4450 3425);
PAINT RED (-4450 3425);
FORCEPROP 2 LAST CDS_LIB mstr_misc
J 0
(-4450 3425);
DISPLAY INVISIBLE (-4450 3425);
FORCEPROP 1 LAST COMMENT_BODY TRUE
R 1
J 0
(-4375 3200);
DISPLAY 0.872340 (-4375 3200);
PAINT GREEN (-4375 3200);
DISPLAY INVISIBLE (-4375 3200);
WIRE 16 -1 (-7650 3775)(-7650 3650);
WIRE 16 -1 (-7075 3850)(-7300 3850);
WIRE 16 -1 (-7300 3850)(-7300 3725);
WIRE 16 -1 (-7325 4400)(-7325 4350);
WIRE 16 -1 (-6975 4975)(-6975 4850);
WIRE 16 -1 (-4425 3325)(-4425 3250);
WIRE 16 -1 (-3525 3900)(-3025 3900);
FORCEPROP 2 LAST SIG_NAME IND_SOC_P1_CPL0
J 0
(-3460 3925);
DISPLAY 0.489362 (-3460 3925);
FORCEPROP 2 LASTPROP $XRERR UNIQUE?
J 0
(-3700 3925);
DISPLAY 0.638298 (-3700 3925);
PAINT MONO (-3700 3925);
DISPLAY INVISIBLE (-3700 3925);
WIRE 16 -1 (-5425 4150)(-4425 4150);
FORCEPROP 2 LAST SIG_NAME SW_PVDDCR_SOC_P1_SW3
J 0
(-5310 4160);
DISPLAY 0.489362 (-5310 4160);
FORCEPROP 2 LASTPROP $XRERR UNIQUE?
J 0
(-5550 4160);
DISPLAY 0.638298 (-5550 4160);
PAINT MONO (-5550 4160);
DISPLAY INVISIBLE (-5550 4160);
WIRE 16 -1 (-4425 4150)(-3025 4150);
WIRE 16 -1 (-4425 4050)(-4425 4150);
WIRE 16 -1 (-1475 4150)(-1475 2950);
WIRE 16 -1 (-1475 4150)(-1400 4150);
WIRE 16 -1 (-2225 4150)(-1475 4150);
WIRE 16 -1 (-1475 2950)(-3875 2950);
WIRE 16 -1 (-1400 4150)(-975 4150);
WIRE 16 -1 (-1400 4150)(-1400 4075);
WIRE 16 -1 (-975 4250)(-975 4150);
WIRE 16 -1 (-975 4150)(-975 4075);
WIRE 16 -1 (-3800 3850)(-3800 3900);
WIRE 16 -1 (-3800 3900)(-3725 3900);
WIRE 16 -1 (-3300 4925)(-3300 4800);
WIRE 16 -1 (-3300 4800)(-3300 4750);
WIRE 16 -1 (-3300 4800)(-3675 4800);
WIRE 16 -1 (-3675 4925)(-3675 4800);
WIRE 16 -1 (-3675 4800)(-3975 4800);
WIRE 16 -1 (-3975 4925)(-3975 4800);
WIRE 16 -1 (-4300 4800)(-3975 4800);
WIRE 16 -1 (-4300 4925)(-4300 4800);
WIRE 16 -1 (-4625 4800)(-4300 4800);
WIRE 16 -1 (-4625 4925)(-4625 4800);
WIRE 16 -1 (-5025 4800)(-4625 4800);
WIRE 16 -1 (-5025 4925)(-5025 4800);
WIRE 16 -1 (-7825 4050)(-7650 4050);
WIRE 16 -1 (-6275 4050)(-7650 4050);
FORCEPROP 2 LAST SIG_NAME PVDDCR_CPU0_P1_VCCS
J 2
(-6335 4060);
DISPLAY 0.489362 (-6335 4060);
WIRE 16 -1 (-7650 3975)(-7650 4050);
WIRE 16 -1 (-6875 3850)(-6275 3850);
FORCEPROP 2 LAST SIG_NAME PVDDCR_SOC_P1_LSET3
J 2
(-6335 3860);
DISPLAY 0.489362 (-6335 3860);
FORCEPROP 2 LASTPROP $XRERR UNIQUE?
J 0
(-6575 3860);
DISPLAY 0.638298 (-6575 3860);
PAINT MONO (-6575 3860);
DISPLAY INVISIBLE (-6575 3860);
WIRE 16 -1 (-6275 3900)(-6725 3900);
FORCEPROP 2 LAST SIG_NAME NC_PVDDCR_SOC_P1_DNC3
J 2
(-6335 3910);
DISPLAY 0.489362 (-6335 3910);
FORCEPROP 2 LASTPROP $XRERR UNIQUE?
J 0
(-6965 3900);
DISPLAY 0.638298 (-6965 3900);
PAINT MONO (-6965 3900);
DISPLAY INVISIBLE (-6965 3900);
WIRE 16 -1 (-6275 3650)(-6900 3650);
FORCEPROP 2 LAST SIG_NAME PVDDCR_SOC_P1_TEMP1
J 2
(-6335 3660);
DISPLAY 0.489362 (-6335 3660);
WIRE 16 -1 (-6275 3550)(-6875 3550);
FORCEPROP 2 LAST SIG_NAME PVDDCR_SOC_P1_PWM3
J 2
(-6335 3560);
DISPLAY 0.489362 (-6335 3560);
WIRE 16 -1 (-5425 3550)(-5250 3550);
WIRE 16 -1 (-5250 3550)(-5250 3600);
WIRE 16 -1 (-5250 3475)(-5250 3550);
WIRE 16 -1 (-5250 3600)(-5250 3650);
WIRE 16 -1 (-5425 3600)(-5250 3600);
WIRE 16 -1 (-5425 3650)(-5250 3650);
WIRE 16 -1 (-5250 3700)(-5250 3650);
WIRE 16 -1 (-5250 3700)(-5425 3700);
WIRE 16 -1 (-5425 3850)(-4900 3850);
FORCEPROP 2 LAST SIG_NAME NC_PVDDCR_SOC_P1_GL1_3
J 0
(-5310 3860);
DISPLAY 0.489362 (-5310 3860);
FORCEPROP 2 LASTPROP $XRERR UNIQUE?
J 0
(-4870 3850);
DISPLAY 0.638298 (-4870 3850);
PAINT MONO (-4870 3850);
DISPLAY INVISIBLE (-4870 3850);
WIRE 16 -1 (-5425 3800)(-4900 3800);
FORCEPROP 2 LAST SIG_NAME NC_PVDDCR_SOC_P1_GL2_3
J 0
(-5310 3810);
DISPLAY 0.489362 (-5310 3810);
FORCEPROP 2 LASTPROP $XRERR UNIQUE?
J 0
(-4870 3800);
DISPLAY 0.638298 (-4870 3800);
PAINT MONO (-4870 3800);
DISPLAY INVISIBLE (-4870 3800);
WIRE 16 -1 (-5425 3900)(-4675 3900);
WIRE 16 -1 (-4675 3900)(-4675 2950);
WIRE 16 -1 (-4075 2950)(-4675 2950);
FORCEPROP 2 LAST SIG_NAME PVDDCR_SOC_P1_VOS3
J 0
(-5310 3925);
DISPLAY 0.489362 (-5310 3925);
FORCEPROP 2 LASTPROP $XRERR UNIQUE?
J 0
(-5550 3925);
DISPLAY 0.638298 (-5550 3925);
PAINT MONO (-5550 3925);
DISPLAY INVISIBLE (-5550 3925);
WIRE 16 -1 (-4425 3850)(-4425 3525);
FORCEPROP 2 LAST SIG_NAME SW_PVDDCR_SOC_P1_SW3_RC
J 0
(-4385 3660);
DISPLAY 0.489362 (-4385 3660);
FORCEPROP 2 LASTPROP $XRERR UNIQUE?
J 0
(-4625 3660);
DISPLAY 0.638298 (-4625 3660);
PAINT MONO (-4625 3660);
DISPLAY INVISIBLE (-4625 3660);
WIRE 16 -1 (-7325 5150)(-7325 5275);
WIRE 16 -1 (-6975 5275)(-7325 5275);
WIRE 16 -1 (-7325 5400)(-7325 5275);
WIRE 16 -1 (-6650 5275)(-6975 5275);
WIRE 16 -1 (-6975 5175)(-6975 5275);
WIRE 16 -1 (-6650 4800)(-6650 5275);
WIRE 16 -1 (-6650 4800)(-6275 4800);
WIRE 16 -1 (-7325 4675)(-6875 4675);
WIRE 16 -1 (-7325 4950)(-7325 4675);
WIRE 16 -1 (-7325 4675)(-7325 4600);
WIRE 16 -1 (-6875 4675)(-6875 4500);
FORCEPROP 2 LAST SIG_NAME PVDDCR_SOC_P1_VCC3
J 2
(-6360 4510);
DISPLAY 0.489362 (-6360 4510);
FORCEPROP 2 LASTPROP $XRERR UNIQUE?
J 0
(-6600 4510);
DISPLAY 0.638298 (-6600 4510);
PAINT MONO (-6600 4510);
DISPLAY INVISIBLE (-6600 4510);
WIRE 16 -1 (-6875 4500)(-6275 4500);
WIRE 16 -1 (-6875 4500)(-6875 4300);
WIRE 16 -1 (-6875 4300)(-6275 4300);
WIRE 16 -1 (-6275 4150)(-6925 4150);
FORCEPROP 2 LAST SIG_NAME PVDDCR_SOC_P1_IMON3
J 2
(-6335 4160);
DISPLAY 0.489362 (-6335 4160);
WIRE 16 -1 (-5325 4800)(-5325 4750);
WIRE 16 -1 (-5425 4800)(-5325 4800);
WIRE 16 -1 (-5325 5200)(-5325 4800);
WIRE 16 -1 (-5325 4750)(-5425 4750);
WIRE 16 -1 (-5325 5200)(-5025 5200);
WIRE 16 -1 (-5025 5200)(-4625 5200);
WIRE 16 -1 (-5025 5125)(-5025 5200);
WIRE 16 -1 (-4625 5200)(-4300 5200);
WIRE 16 -1 (-4625 5125)(-4625 5200);
WIRE 16 -1 (-4300 5200)(-3975 5200);
WIRE 16 -1 (-4300 5125)(-4300 5200);
WIRE 16 -1 (-3975 5200)(-3675 5200);
WIRE 16 -1 (-3975 5200)(-3975 5125);
WIRE 16 -1 (-3300 5200)(-3675 5200);
WIRE 16 -1 (-3675 5200)(-3675 5125);
WIRE 16 -1 (-3300 5250)(-3300 5200);
WIRE 16 -1 (-3300 5200)(-3300 5125);
WIRE 16 -1 (-5425 4500)(-4550 4500);
FORCEPROP 2 LAST SIG_NAME SW_PVDDCR_SOC_P1_BOOT3
J 0
(-5310 4510);
DISPLAY 0.489362 (-5310 4510);
FORCEPROP 2 LASTPROP $XRERR UNIQUE?
J 0
(-5550 4510);
DISPLAY 0.638298 (-5550 4510);
PAINT MONO (-5550 4510);
DISPLAY INVISIBLE (-5550 4510);
WIRE 16 -1 (-2225 3900)(-1875 3900);
FORCEPROP 2 LAST SIG_NAME IND_SOC_P1_CPL3
J 0
(-2185 3910);
DISPLAY 0.489362 (-2185 3910);
WIRE 16 -1 (-1400 3875)(-1400 3750);
WIRE 16 -1 (-975 3750)(-1400 3750);
WIRE 16 -1 (-975 3875)(-975 3750);
WIRE 16 -1 (-975 3675)(-975 3750);
WIRE 16 -1 (-3475 4275)(-3475 4250);
WIRE 16 -1 (-3475 4250)(-5425 4250);
FORCEPROP 2 LAST SIG_NAME SW_PVDDCR_SOC_P1_PH3
J 0
(-5310 4260);
DISPLAY 0.489362 (-5310 4260);
FORCEPROP 2 LASTPROP $XRERR UNIQUE?
J 0
(-5550 4260);
DISPLAY 0.638298 (-5550 4260);
PAINT MONO (-5550 4260);
DISPLAY INVISIBLE (-5550 4260);
WIRE 16 -1 (-4350 4500)(-3475 4500);
FORCEPROP 2 LAST SIG_NAME SW_PVDDCR_SOC_P1_BOOT3_RC
J 2
(-3510 4510);
DISPLAY 0.489362 (-3510 4510);
FORCEPROP 2 LASTPROP $XRERR UNIQUE?
J 0
(-3750 4510);
DISPLAY 0.638298 (-3750 4510);
PAINT MONO (-3750 4510);
DISPLAY INVISIBLE (-3750 4510);
WIRE 16 -1 (-3475 4500)(-3475 4475);
DOT 1 (-7325 5275);
DOT 1 (-4425 4150);
DOT 1 (-6875 4500);
DOT 1 (-6975 5275);
DOT 1 (-975 3750);
DOT 1 (-1400 4150);
DOT 1 (-1475 4150);
DOT 1 (-3975 4800);
DOT 1 (-4300 5200);
DOT 1 (-4625 5200);
DOT 1 (-5025 5200);
DOT 1 (-4300 4800);
DOT 1 (-4625 4800);
DOT 1 (-5325 4800);
DOT 1 (-7325 4675);
DOT 1 (-5250 3600);
DOT 1 (-5250 3550);
DOT 1 (-7650 4050);
DOT 1 (-3975 5200);
DOT 1 (-3675 5200);
DOT 1 (-3675 4800);
DOT 1 (-3300 5200);
DOT 1 (-3300 4800);
DOT 1 (-975 4150);
DOT 1 (-5250 3650);
FORCENOTE
HCME656510Q-221QL
(-3700 3850) 0;
DISPLAY LEFT (-3700 3850);
DISPLAY 0.638298 (-3700 3850);
PAINT WHITE (-3700 3850);
FORCENOTE
2ND=CV+22Y0EZ01
(-3700 3650) 0;
DISPLAY LEFT (-3700 3650);
DISPLAY 0.638298 (-3700 3650);
PAINT WHITE (-3700 3650);
FORCENOTE
ISAT:30A@100C
(-3700 3800) 0;
DISPLAY LEFT (-3700 3800);
DISPLAY 0.638298 (-3700 3800);
PAINT WHITE (-3700 3800);
FORCENOTE
PVDDCR_SOC_P1_PHASE3
(-6400 5550) 0;
DISPLAY LEFT (-6400 5550);
DISPLAY 1.595745 (-6400 5550);
PAINT WHITE (-6400 5550);
FORCENOTE
DCR=2-3,0.27M OHM
(-2225 4275) 0;
DISPLAY LEFT (-2225 4275);
DISPLAY 0.638298 (-2225 4275);
PAINT WHITE (-2225 4275);
FORCENOTE
PGL6303.151HLT
(-2225 4475) 0;
DISPLAY LEFT (-2225 4475);
DISPLAY 0.638298 (-2225 4475);
PAINT WHITE (-2225 4475);
FORCENOTE
ISAT:70A@100C
(-2225 4425) 0;
DISPLAY LEFT (-2225 4425);
DISPLAY 0.638298 (-2225 4425);
PAINT WHITE (-2225 4425);
FORCENOTE
11.0*7.5*12.5
(-2225 4375) 0;
DISPLAY LEFT (-2225 4375);
DISPLAY 0.638298 (-2225 4375);
PAINT WHITE (-2225 4375);
FORCENOTE
DCR=1-4,0.105M OHM
(-2225 4325) 0;
DISPLAY LEFT (-2225 4325);
DISPLAY 0.638298 (-2225 4325);
PAINT WHITE (-2225 4325);
FORCENOTE
2ND=CV+15^0TZ01
(-2225 4225) 0;
DISPLAY LEFT (-2225 4225);
DISPLAY 0.638298 (-2225 4225);
PAINT WHITE (-2225 4225);
FORCENOTE
DCR=0.17M OHM
(-3700 3700) 0;
DISPLAY LEFT (-3700 3700);
DISPLAY 0.638298 (-3700 3700);
PAINT WHITE (-3700 3700);
FORCENOTE
6.5*6.5*10.0
(-3700 3750) 0;
DISPLAY LEFT (-3700 3750);
DISPLAY 0.638298 (-3700 3750);
PAINT WHITE (-3700 3750);
QUIT
